# T6G (Grand Teton) — schematic netlist excerpt (pin names and nets, part order shuffled) for the footprints in the layout excerpt that follows; sources: Cadence DE-HDL packaged netlist, KiCad conversion of 04192023_DAF0TMB3IC0_F0TG_MB_C_brd_V02_OCP.brd

JP12  CONN3_210HP1030BR1  CONN3_210-HP1-030BR1 IO  pkg HEADER1X3XG  page 187
  \1\  = P1V5_BAT_OUT_R
  \2\  = P1V5_BAT
  \3\  = GND

PR3928  Q_RES  0 5% CHIP  pkg 0402LF  page 262 : A = HSC_ON ; B = HSC_ON_R

(kicad_pcb
	(version 20260206)
	(generator "pcbnew")
	(generator_version "10.0")
	(general
		(thickness 1.6)
		(legacy_teardrops no)
	)
	(paper "A4")
	(title_block
		(title "04192023_DAF0TMB3IC0_F0TG_MB_C_brd_V02_OCP.brd")
		(comment 1 "Grand Teton / footprints 3964-3965 of 8354")
	)
	(layers
		(0 "F.Cu" signal "TOP")
		(4 "In1.Cu" signal "GND")
		(6 "In2.Cu" signal "IN1")
		(8 "In3.Cu" signal "GND1")
		(10 "In4.Cu" signal "IN2")
		(12 "In5.Cu" signal "GND2")
		(14 "In6.Cu" signal "IN3")
		(16 "In7.Cu" signal "GND3")
		(18 "In8.Cu" signal "VCC")
		(20 "In9.Cu" signal "VCC1")
		(22 "In10.Cu" signal "GND4")
		(24 "In11.Cu" signal "IN4")
		(26 "In12.Cu" signal "GND5")
		(28 "In13.Cu" signal "IN5")
		(30 "In14.Cu" signal "GND6")
		(32 "In15.Cu" signal "IN6")
		(34 "In16.Cu" signal "GND7")
		(2 "B.Cu" signal "BOTTOM")
		(9 "F.Adhes" user "F.Adhesive")
		(11 "B.Adhes" user "B.Adhesive")
		(13 "F.Paste" user "Package Geometry/Pastemask Top")
		(15 "B.Paste" user "Package Geometry/Pastemask Bottom")
		(5 "F.SilkS" user "Ref Des/Silkscreen Top")
		(7 "B.SilkS" user "Ref Des/Silkscreen Bottom")
		(1 "F.Mask" user "Board Geometry/Soldermask Top")
		(3 "B.Mask" user "Board Geometry/Soldermask Bottom")
		(17 "Dwgs.User" user "User.Drawings")
		(19 "Cmts.User" user "User.Comments")
		(21 "Eco1.User" user "User.Eco1")
		(23 "Eco2.User" user "User.Eco2")
		(25 "Edge.Cuts" user "Board Geometry/Outline")
		(27 "Margin" user)
		(31 "F.CrtYd" user "Package Geometry/Place Bound Top")
		(29 "B.CrtYd" user "Package Geometry/Place Bound Bottom")
		(35 "F.Fab" user "Ref Des/Assembly Top")
		(33 "B.Fab" user "Ref Des/Assembly Bottom")
	)
	(footprint ""
		(layer "F.Cu")
		(at 191.41694 -401.325842 180)
		(property "Reference" "PR3928"
			(at 0 0 180)
			(layer "F.SilkS")
			(hide yes)
			(effects
				(font
					(size 1.27 1.27)
				)
			)
		)
		(property "Value" ""
			(at 0 0 180)
			(layer "F.Fab")
			(effects
				(font
					(size 1.27 1.27)
				)
			)
		)
		(duplicate_pad_numbers_are_jumpers no)
		(fp_line
			(start 0.7874 0.4064)
			(end -0.7874 0.4064)
			(stroke
				(width 0.1524)
				(type default)
			)
			(layer "F.SilkS")
		)
		(fp_line
			(start 0.7874 -0.4064)
			(end 0.7874 0.4064)
			(stroke
				(width 0.1524)
				(type default)
			)
			(layer "F.SilkS")
		)
		(fp_line
			(start -0.7874 0.4064)
			(end -0.7874 -0.4064)
			(stroke
				(width 0.1524)
				(type default)
			)
			(layer "F.SilkS")
		)
		(fp_line
			(start -0.7874 -0.4064)
			(end 0.7874 -0.4064)
			(stroke
				(width 0.1524)
				(type default)
			)
			(layer "F.SilkS")
		)
		(fp_line
			(start 0.67945 0.3048)
			(end 0.120396 0.3048)
			(stroke
				(width 0.1)
				(type default)
			)
			(layer "F.Fab")
		)
		(fp_line
			(start 0.67945 -0.3048)
			(end 0.67945 0.3048)
			(stroke
				(width 0.1)
				(type default)
			)
			(layer "F.Fab")
		)
		(fp_line
			(start 0.12065 -0.2794)
			(end 0.12065 -0.3048)
			(stroke
				(width 0.1)
				(type default)
			)
			(layer "F.Fab")
		)
		(fp_line
			(start 0.12065 -0.3048)
			(end 0.67945 -0.3048)
			(stroke
				(width 0.1)
				(type default)
			)
			(layer "F.Fab")
		)
		(fp_line
			(start 0.120396 0.3048)
			(end 0.120396 0.2794)
			(stroke
				(width 0.1)
				(type default)
			)
			(layer "F.Fab")
		)
		(fp_line
			(start 0.120396 0.2794)
			(end -0.12065 0.2794)
			(stroke
				(width 0.1)
				(type default)
			)
			(layer "F.Fab")
		)
		(fp_line
			(start -0.12065 0.3048)
			(end -0.67945 0.3048)
			(stroke
				(width 0.1)
				(type default)
			)
			(layer "F.Fab")
		)
		(fp_line
			(start -0.12065 0.2794)
			(end -0.12065 0.3048)
			(stroke
				(width 0.1)
				(type default)
			)
			(layer "F.Fab")
		)
		(fp_line
			(start -0.12065 -0.2794)
			(end 0.12065 -0.2794)
			(stroke
				(width 0.1)
				(type default)
			)
			(layer "F.Fab")
		)
		(fp_line
			(start -0.12065 -0.305054)
			(end -0.12065 -0.2794)
			(stroke
				(width 0.1)
				(type default)
			)
			(layer "F.Fab")
		)
		(fp_line
			(start -0.67945 0.3048)
			(end -0.67945 -0.305054)
			(stroke
				(width 0.1)
				(type default)
			)
			(layer "F.Fab")
		)
		(fp_line
			(start -0.67945 -0.305054)
			(end -0.12065 -0.305054)
			(stroke
				(width 0.1)
				(type default)
			)
			(layer "F.Fab")
		)
		(pad "1" smd circle
			(at -0.40005 0 180)
			(size 0 0)
			(layers "F.Cu" "F.Mask" "F.Paste")
			(net "HSC_ON")
		)
		(pad "2" smd circle
			(at 0.40005 0 180)
			(size 0 0)
			(layers "F.Cu" "F.Mask" "F.Paste")
			(net "HSC_ON_R")
		)
	)
	(footprint ""
		(layer "F.Cu")
		(at 330.057506 -23.574248 180)
		(property "Reference" "JP12"
			(at 2.044446 -1.387094 90)
			(unlocked yes)
			(layer "F.SilkS")
			(effects
				(font
					(size 0.7874 0.5842)
					(thickness 0.1524)
				)
				(justify left)
			)
		)
		(property "Value" ""
			(at 0 0 180)
			(layer "F.Fab")
			(effects
				(font
					(size 1.27 1.27)
				)
			)
		)
		(duplicate_pad_numbers_are_jumpers no)
		(fp_line
			(start 1.249934 6.400038)
			(end -1.249934 6.400038)
			(stroke
				(width 0.1524)
				(type default)
			)
			(layer "F.SilkS")
		)
		(fp_line
			(start 1.249934 -1.320038)
			(end 1.249934 6.400038)
			(stroke
				(width 0.1524)
				(type default)
			)
			(layer "F.SilkS")
		)
		(fp_line
			(start -1.249934 6.400038)
			(end -1.249934 -1.320038)
			(stroke
				(width 0.1524)
				(type default)
			)
			(layer "F.SilkS")
		)
		(fp_line
			(start -1.249934 -1.320038)
			(end 1.249934 -1.320038)
			(stroke
				(width 0.1524)
				(type default)
			)
			(layer "F.SilkS")
		)
		(fp_poly
			(pts
				(xy -2.382266 0.655828) (xy -1.465072 0.410972) (xy -1.819402 1.291844)
			)
			(stroke
				(width 0)
				(type default)
			)
			(fill yes)
			(layer "F.SilkS")
		)
		(fp_line
			(start 1.249934 6.400038)
			(end -1.249934 6.400038)
			(stroke
				(width 0.1)
				(type default)
			)
			(layer "F.Fab")
		)
		(fp_line
			(start 1.249934 -1.320038)
			(end 1.249934 6.400038)
			(stroke
				(width 0.1)
				(type default)
			)
			(layer "F.Fab")
		)
		(fp_line
			(start -1.249934 6.400038)
			(end -1.249934 -1.320038)
			(stroke
				(width 0.1)
				(type default)
			)
			(layer "F.Fab")
		)
		(fp_line
			(start -1.249934 -1.320038)
			(end 1.249934 -1.320038)
			(stroke
				(width 0.1)
				(type default)
			)
			(layer "F.Fab")
		)
		(fp_poly
			(pts
				(xy -2.5654 -0.556514) (xy -1.452372 0) (xy -2.5654 0.556514)
			)
			(stroke
				(width 0)
				(type default)
			)
			(fill yes)
			(layer "F.Fab")
		)
		(fp_text user "3"
			(at -1.778 5.13207 180)
			(unlocked yes)
			(layer "F.SilkS")
			(effects
				(font
					(size 0.7874 0.5842)
					(thickness 0.1524)
				)
			)
		)
		(fp_text user "1"
			(at -1.143 0.02667 180)
			(unlocked yes)
			(layer "B.SilkS")
			(effects
				(font
					(size 0.7874 0.5842)
					(thickness 0.1524)
				)
				(justify mirror)
			)
		)
		(fp_text user "3"
			(at -1.1557 5.18287 180)
			(unlocked yes)
			(layer "B.SilkS")
			(effects
				(font
					(size 0.7874 0.5842)
					(thickness 0.1524)
				)
				(justify mirror)
			)
		)
		(fp_text user "1"
			(at -1.143 0.02667 180)
			(unlocked yes)
			(layer "B.Fab")
			(effects
				(font
					(size 0.7874 0.5842)
					(thickness 0.1524)
				)
				(justify mirror)
			)
		)
		(fp_text user "3"
			(at -1.1557 5.18287 180)
			(unlocked yes)
			(layer "B.Fab")
			(effects
				(font
					(size 0.7874 0.5842)
					(thickness 0.1524)
				)
				(justify mirror)
			)
		)
		(fp_text user "3"
			(at -1.778 5.13207 180)
			(unlocked yes)
			(layer "F.Fab")
			(effects
				(font
					(size 0.7874 0.5842)
					(thickness 0.1524)
				)
			)
		)
		(pad "1" thru_hole rect
			(at 0 0 180)
			(size 1.5494 1.5494)
			(drill 1.0414)
			(layers "*.Cu" "*.Mask")
			(remove_unused_layers no)
			(net "P1V5_BAT_OUT_R")
			(clearance 0)
			(padstack
				(mode front_inner_back)
				(layer "Inner"
					(shape circle)
					(size 1.5494 1.5494)
					(clearance 0)
				)
				(layer "B.Cu"
					(shape rect)
					(size 1.5494 1.5494)
					(clearance 0)
				)
			)
		)
		(pad "2" thru_hole circle
			(at 0 2.54 180)
			(size 1.5494 1.5494)
			(drill 1.0414)
			(layers "*.Cu" "*.Mask")
			(remove_unused_layers no)
			(net "P1V5_BAT")
			(clearance 0)
		)
		(pad "3" thru_hole circle
			(at 0 5.08 180)
			(size 1.5494 1.5494)
			(drill 1.0414)
			(layers "*.Cu" "*.Mask")
			(remove_unused_layers no)
			(net "GND")
			(clearance 0)
		)
	)
)
